# S9S_MB_2U (Grand Teton) — schematic netlist excerpt (pin names and nets, part order shuffled) for the footprints in the layout excerpt that follows; sources: Cadence DE-HDL packaged netlist, KiCad conversion of 03242023_DA0F0TMBIJ0_F0T_Motherboard_J_brd_V01_OCP.brd

J2  SCONN288_ADR50017P087CC  SCONN288_ADR50017-P087CC IO  pkg DDR288S_1-1VXB  page 83
  VIN_BULK0  = P12V_S3_AUX_CPU0_NVDIMM
  RFU0  = TP_CHA_CPU0_DIMM2_FRU_0
  VIN_MGMT  = P3V3_AUX
  HSCL  = I3C_SPD_DDRABCD_CPU0_LVC1_SCL_1
  HSDA  = I3C_SPD_DDRABCD_CPU0_LVC1_SDA
  VSS0  = GND
  DQ0_A  = M_A_CPU0_SA_DQ<0>
  VSS1  = GND
  DQ1_A  = M_A_CPU0_SA_DQ<1>
  VSS2  = GND
  DQS0_A_T  = M_A_CPU0_SA_DQS_DP<0>
  DQS0_A_C  = M_A_CPU0_SA_DQS_DN<0>
  VSS3  = GND
  DQ4_A  = M_A_CPU0_SA_DQ<4>
  VSS4  = GND
  DQ5_A  = M_A_CPU0_SA_DQ<5>
  VSS5  = GND
  DQ8_A  = M_A_CPU0_SA_DQ<8>
  VSS6  = GND
  DQ9_A  = M_A_CPU0_SA_DQ<9>
  VSS7  = GND
  DQS1_A_T  = M_A_CPU0_SA_DQS_DP<1>
  DQS1_A_C  = M_A_CPU0_SA_DQS_DN<1>
  VSS8  = GND
  DQ12_A  = M_A_CPU0_SA_DQ<12>
  VSS9  = GND
  DQ13_A  = M_A_CPU0_SA_DQ<13>
  VSS10  = GND
  DQ16_A  = M_A_CPU0_SA_DQ<16>
  VSS11  = GND
  DQ17_A  = M_A_CPU0_SA_DQ<17>
  VSS12  = GND
  DQS2_A_T  = M_A_CPU0_SA_DQS_DP<2>
  DQS2_A_C  = M_A_CPU0_SA_DQS_DN<2>
  VSS13  = GND
  DQ20_A  = M_A_CPU0_SA_DQ<20>
  VSS14  = GND
  DQ21_A  = M_A_CPU0_SA_DQ<21>
  VSS15  = GND
  DQ24_A  = M_A_CPU0_SA_DQ<24>
  VSS16  = GND
  DQ25_A  = M_A_CPU0_SA_DQ<25>
  VSS17  = GND
  DQS3_A_T  = M_A_CPU0_SA_DQS_DP<3>
  DQS3_A_C  = M_A_CPU0_SA_DQS_DN<3>
  VSS18  = GND
  DQ28_A  = M_A_CPU0_SA_DQ<28>
  VSS19  = GND
  DQ29_A  = M_A_CPU0_SA_DQ<29>
  VSS20  = GND
  CB0_A  = M_A_CPU0_SA_CB<0>
  VSS21  = GND
  CB1_A  = M_A_CPU0_SA_CB<1>
  VSS22  = GND
  DQS4_A_T  = M_A_CPU0_SA_DQS_DP<4>
  DQS4_A_C  = M_A_CPU0_SA_DQS_DN<4>
  VSS23  = GND
  CB4_A  = M_A_CPU0_SA_CB<4>
  VSS24  = GND
  CB5_A  = M_A_CPU0_SA_CB<5>
  VSS25  = GND
  ALERT_N  = M_A_CPU0_ALERT_N
  VSS26  = GND
  CS0_A_N  = M_A_CPU0_SA_CS_N<2>
  VSS27  = GND
  CA0_A  = M_A_CPU0_SA_CA<0>
  VSS28  = GND
  CA2_A  = M_A_CPU0_SA_CA<2>
  VSS29  = GND
  CA4_A  = M_A_CPU0_SA_CA<4>
  VSS30  = GND
  CA6_A  = M_A_CPU0_SA_CA<6>
  VSS31  = GND
  PAR_A  = M_A_CPU0_SA_PAR
  VSS32  = GND
  CA0_B  = M_A_CPU0_SB_CA<0>
  VSS33  = GND
  CA2_B  = M_A_CPU0_SB_CA<2>
  VSS34  = GND
  CA4_B  = M_A_CPU0_SB_CA<4>
  VSS35  = GND
  CA6_B  = M_A_CPU0_SB_CA<6>
  VSS36  = GND
  CS0_B_N  = M_A_CPU0_SB_CS_N<2>
  VSS37  = GND
  \lbd||rsp_a_n\  = M_A_CPU0_SA_RSP<1>
  \lbs||rsp_b_n\  = M_A_CPU0_SB_RSP<1>
  VSS38  = GND
  CB4_B  = M_A_CPU0_SB_CB<4>
  VSS39  = GND
  CB5_B  = M_A_CPU0_SB_CB<5>
  VSS40  = GND
  \dqs9_b_t||tdqs9_b_t||dbi4_b_n\  = M_A_CPU0_SB_DQS_DP<9>
  \dqs9_b_c||tdqs9_b_c\  = M_A_CPU0_SB_DQS_DN<9>
  VSS41  = GND
  CB0_B  = M_A_CPU0_SB_CB<0>
  VSS42  = GND
  CB1_B  = M_A_CPU0_SB_CB<1>
  VSS43  = GND
  DQ0_B  = M_A_CPU0_SB_DQ<0>
  VSS44  = GND
  DQ1_B  = M_A_CPU0_SB_DQ<1>
  VSS45  = GND
  DQS0_B_T  = M_A_CPU0_SB_DQS_DP<0>
  DQS0_B_C  = M_A_CPU0_SB_DQS_DN<0>
  VSS46  = GND
  DQ4_B  = M_A_CPU0_SB_DQ<4>
  VSS47  = GND
  DQ5_B  = M_A_CPU0_SB_DQ<5>
  VSS48  = GND
  DQ8_B  = M_A_CPU0_SB_DQ<8>
  VSS49  = GND
  DQ9_B  = M_A_CPU0_SB_DQ<9>
  VSS50  = GND
  DQS1_B_T  = M_A_CPU0_SB_DQS_DP<1>
  DQS1_B_C  = M_A_CPU0_SB_DQS_DN<1>
  VSS51  = GND
  DQ12_B  = M_A_CPU0_SB_DQ<12>
  VSS52  = GND
  DQ13_B  = M_A_CPU0_SB_DQ<13>
  VSS53  = GND
  DQ16_B  = M_A_CPU0_SB_DQ<16>
  VSS54  = GND
  DQ17_B  = M_A_CPU0_SB_DQ<17>
  VSS55  = GND
  DQS2_B_T  = M_A_CPU0_SB_DQS_DP<2>
  DQS2_B_C  = M_A_CPU0_SB_DQS_DN<2>
  VSS56  = GND
  DQ20_B  = M_A_CPU0_SB_DQ<20>
  VSS57  = GND
  DQ21_B  = M_A_CPU0_SB_DQ<21>
  VSS58  = GND
  DQ24_B  = M_A_CPU0_SB_DQ<24>
  VSS59  = GND
  DQ25_B  = M_A_CPU0_SB_DQ<25>
  VSS60  = GND
  DQS3_B_T  = M_A_CPU0_SB_DQS_DP<3>
  DQS3_B_C  = M_A_CPU0_SB_DQS_DN<3>
  VSS61  = GND
  DQ28_B  = M_A_CPU0_SB_DQ<28>
  VSS62  = GND
  DQ29_B  = M_A_CPU0_SB_DQ<29>
  VSS63  = GND
  RFU1  = TP_CHA_CPU0_DIMM2_FRU_1
  VIN_BULK1  = P12V_S3_AUX_CPU0_NVDIMM
  VIN_BULK2  = P12V_S3_AUX_CPU0_NVDIMM
  \pwr_good||fail_n\  = PWRGD_CHA_CPU0_DIMM2
  HSA  = PD_CHA_CPU0_DIMM2_SAA
  RFU2  = TP_CHA_CPU0_DIMM2_FRU_2
  RFU3  = TP_CHA_CPU0_DIMM2_FRU_3
  VSS64  = GND
  DQ2_A  = M_A_CPU0_SA_DQ<2>
  VSS65  = GND
  DQ3_A  = M_A_CPU0_SA_DQ<3>
  VSS66  = GND
  \dqs5_a_c||tdqs5_a_c||dqs5_a_t||tdqs5_a_t\  = M_A_CPU0_SA_DQS_DN<5>
  \dqs5_a_t||tdqs5_a_t\  = M_A_CPU0_SA_DQS_DP<5>
  VSS67  = GND
  DQ6_A  = M_A_CPU0_SA_DQ<6>
  VSS68  = GND
  DQ7_A  = M_A_CPU0_SA_DQ<7>
  VSS69  = GND
  DQ10_A  = M_A_CPU0_SA_DQ<10>
  VSS70  = GND
  DQ11_A  = M_A_CPU0_SA_DQ<11>
  VSS71  = GND
  \dqs6_a_c||tdqs6_a_c||dqs6_a_t||tdqs6_a_t\  = M_A_CPU0_SA_DQS_DN<6>
  \dqs6_a_t||tdqs6_a_t\  = M_A_CPU0_SA_DQS_DP<6>
  VSS72  = GND
  DQ14_A  = M_A_CPU0_SA_DQ<14>
  VSS73  = GND
  DQ15_A  = M_A_CPU0_SA_DQ<15>
  VSS74  = GND
  DQ18_A  = M_A_CPU0_SA_DQ<18>
  VSS75  = GND
  DQ19_A  = M_A_CPU0_SA_DQ<19>
  VSS76  = GND
  \dqs7_a_c||tdqs7_a_c\  = M_A_CPU0_SA_DQS_DN<7>
  \dqs7_a_t||tdqs7_a_t\  = M_A_CPU0_SA_DQS_DP<7>
  VSS77  = GND
  DQ22_A  = M_A_CPU0_SA_DQ<22>
  VSS78  = GND
  DQ23_A  = M_A_CPU0_SA_DQ<23>
  VSS79  = GND
  DQ26_A  = M_A_CPU0_SA_DQ<26>
  VSS80  = GND
  DQ27_A  = M_A_CPU0_SA_DQ<27>
  VSS81  = GND
  \dqs8_a_c||tdqs8_a_c\  = M_A_CPU0_SA_DQS_DN<8>
  \dqs8_a_t||tdqs8_a_t\  = M_A_CPU0_SA_DQS_DP<8>
  VSS82  = GND
  DQ30_A  = M_A_CPU0_SA_DQ<30>
  VSS83  = GND
  DQ31_A  = M_A_CPU0_SA_DQ<31>
  VSS84  = GND
  CB2_A  = M_A_CPU0_SA_CB<2>
  VSS85  = GND
  CB3_A  = M_A_CPU0_SA_CB<3>
  VSS86  = GND
  \dqs9_a_c||tdqs9_a_c\  = M_A_CPU0_SA_DQS_DN<9>
  \dqs9_a_t||tdqs9_a_t\  = M_A_CPU0_SA_DQS_DP<9>
  VSS87  = GND
  CB6_A  = M_A_CPU0_SA_CB<6>
  VSS88  = GND
  CB7_A  = M_A_CPU0_SA_CB<7>
  VSS89  = GND
  RESET_N  = RST_M_AB_CPU0_FPGA_N
  VSS90  = GND
  CS1_A_N  = M_A_CPU0_SA_CS_N<3>
  VSS91  = GND
  CA1_A  = M_A_CPU0_SA_CA<1>
  VSS92  = GND
  CA3_A  = M_A_CPU0_SA_CA<3>
  VSS93  = GND
  CA5_A  = M_A_CPU0_SA_CA<5>
  VSS94  = GND
  CK_T  = M_A_CPU0_CLK_DP<1>
  CK_C  = M_A_CPU0_CLK_DN<1>
  VSS95  = GND
  RFU4  = TP_CHA_CPU0_DIMM2_FRU_4
  CA1_B  = M_A_CPU0_SB_CA<1>
  VSS96  = GND
  CA3_B  = M_A_CPU0_SB_CA<3>
  VSS97  = GND
  CA5_B  = M_A_CPU0_SB_CA<5>
  VSS98  = GND
  PAR_B  = M_A_CPU0_SB_PAR
  VSS99  = GND
  CS1_B_N  = M_A_CPU0_SB_CS_N<3>
  VSS100  = GND
  RFU5  = TP_CHA_CPU0_DIMM2_FRU_5
  RFU6  = TP_CHA_CPU0_DIMM2_FRU_6
  VSS101  = GND
  CB6_B  = M_A_CPU0_SB_CB<6>
  VSS102  = GND
  CB7_B  = M_A_CPU0_SB_CB<7>
  VSS103  = GND
  DQS4_B_C  = M_A_CPU0_SB_DQS_DN<4>
  DQS4_B_T  = M_A_CPU0_SB_DQS_DP<4>
  VSS104  = GND
  CB2_B  = M_A_CPU0_SB_CB<2>
  VSS105  = GND
  CB3_B  = M_A_CPU0_SB_CB<3>
  VSS106  = GND
  DQ2_B  = M_A_CPU0_SB_DQ<2>
  VSS107  = GND
  DQ3_B  = M_A_CPU0_SB_DQ<3>
  VSS108  = GND
  \dqs5_b_c||tdqs5_b_c\  = M_A_CPU0_SB_DQS_DN<5>
  \dqs5_b_t||tdqs5_b_t\  = M_A_CPU0_SB_DQS_DP<5>
  VSS109  = GND
  DQ6_B  = M_A_CPU0_SB_DQ<6>
  VSS110  = GND
  DQ7_B  = M_A_CPU0_SB_DQ<7>
  VSS111  = GND
  DQ10_B  = M_A_CPU0_SB_DQ<10>
  VSS112  = GND
  DQ11_B  = M_A_CPU0_SB_DQ<11>
  VSS113  = GND
  \dqs6_b_c||tdqs6_b_c\  = M_A_CPU0_SB_DQS_DN<6>
  \dqs6_b_t||tdqs6_b_t\  = M_A_CPU0_SB_DQS_DP<6>
  VSS114  = GND
  DQ14_B  = M_A_CPU0_SB_DQ<14>
  VSS115  = GND
  DQ15_B  = M_A_CPU0_SB_DQ<15>
  VSS116  = GND
  DQ18_B  = M_A_CPU0_SB_DQ<18>
  VSS117  = GND
  DQ19_B  = M_A_CPU0_SB_DQ<19>
  VSS118  = GND
  \dqs7_b_c||tdqs7_b_c\  = M_A_CPU0_SB_DQS_DN<7>
  \dqs7_b_t||tdqs7_b_t\  = M_A_CPU0_SB_DQS_DP<7>
  VSS119  = GND
  DQ22_B  = M_A_CPU0_SB_DQ<22>
  VSS120  = GND
  DQ23_B  = M_A_CPU0_SB_DQ<23>
  VSS121  = GND
  DQ26_B  = M_A_CPU0_SB_DQ<26>
  VSS122  = GND
  DQ27_B  = M_A_CPU0_SB_DQ<27>
  VSS123  = GND
  \dqs8_b_c||tdqs8_b_c\  = M_A_CPU0_SB_DQS_DN<8>
  \dqs8_b_t||tdqs8_b_t\  = M_A_CPU0_SB_DQS_DP<8>
  VSS124  = GND
  DQ30_B  = M_A_CPU0_SB_DQ<30>
  VSS125  = GND
  DQ31_B  = M_A_CPU0_SB_DQ<31>
  VSS126  = GND
  G1  = GND
  G2  = GND
  G3  = GND

(kicad_pcb
	(version 20260206)
	(generator "pcbnew")
	(generator_version "10.0")
	(general
		(thickness 1.6)
		(legacy_teardrops no)
	)
	(paper "A4")
	(title_block
		(title "03242023_DA0F0TMBIJ0_F0T_Motherboard_J_brd_V01_OCP.brd")
		(comment 1 "Grand Teton / footprint 2856 of 6105 (J2), pads 46-91 of 291")
	)
	(layers
		(0 "F.Cu" signal "TOP")
		(4 "In1.Cu" signal "GND")
		(6 "In2.Cu" signal "IN1")
		(8 "In3.Cu" signal "GND1")
		(10 "In4.Cu" signal "IN2")
		(12 "In5.Cu" signal "GND2")
		(14 "In6.Cu" signal "IN3")
		(16 "In7.Cu" signal "GND3")
		(18 "In8.Cu" signal "VCC")
		(20 "In9.Cu" signal "VCC1")
		(22 "In10.Cu" signal "GND4")
		(24 "In11.Cu" signal "IN4")
		(26 "In12.Cu" signal "GND5")
		(28 "In13.Cu" signal "IN5")
		(30 "In14.Cu" signal "GND6")
		(32 "In15.Cu" signal "IN6")
		(34 "In16.Cu" signal "GND7")
		(2 "B.Cu" signal "BOTTOM")
		(9 "F.Adhes" user "F.Adhesive")
		(11 "B.Adhes" user "B.Adhesive")
		(13 "F.Paste" user "Package Geometry/Pastemask Top")
		(15 "B.Paste" user "Package Geometry/Pastemask Bottom")
		(5 "F.SilkS" user "Ref Des/Silkscreen Top")
		(7 "B.SilkS" user "Ref Des/Silkscreen Bottom")
		(1 "F.Mask" user "Board Geometry/Soldermask Top")
		(3 "B.Mask" user "Board Geometry/Soldermask Bottom")
		(17 "Dwgs.User" user "User.Drawings")
		(19 "Cmts.User" user "User.Comments")
		(21 "Eco1.User" user "User.Eco1")
		(23 "Eco2.User" user "User.Eco2")
		(25 "Edge.Cuts" user "Board Geometry/Outline")
		(27 "Margin" user)
		(31 "F.CrtYd" user "Package Geometry/Place Bound Top")
		(29 "B.CrtYd" user "Package Geometry/Place Bound Bottom")
		(35 "F.Fab" user "Ref Des/Assembly Top")
		(33 "B.Fab" user "Ref Des/Assembly Bottom")
	)
	(footprint ""
		(layer "F.Cu")
		(at 310.937148 -258.091686)
		(property "Reference" "J2"
			(at -3.683 -81.702148 0)
			(unlocked yes)
			(layer "F.SilkS")
			(effects
				(font
					(size 0.7874 0.5842)
					(thickness 0.1524)
				)
				(justify left)
			)
		)
		(property "Value" ""
			(at 0 0 0)
			(layer "F.Fab")
			(effects
				(font
					(size 1.27 1.27)
				)
			)
		)
		(duplicate_pad_numbers_are_jumpers no)
		(pad "46" smd rect
			(at -2.050034 -25.07488 270)
			(size 0.519938 1.4986)
			(layers "F.Cu" "F.Mask" "F.Paste")
			(net "GND")
		)
		(pad "47" smd rect
			(at -2.050034 -24.224996 270)
			(size 0.519938 1.4986)
			(layers "F.Cu" "F.Mask" "F.Paste")
			(net "M_A_CPU0_SA_DQ<28>")
		)
		(pad "48" smd rect
			(at -2.050034 -23.375112 270)
			(size 0.519938 1.4986)
			(layers "F.Cu" "F.Mask" "F.Paste")
			(net "GND")
		)
		(pad "49" smd rect
			(at -2.050034 -22.524974 270)
			(size 0.519938 1.4986)
			(layers "F.Cu" "F.Mask" "F.Paste")
			(net "M_A_CPU0_SA_DQ<29>")
		)
		(pad "50" smd rect
			(at -2.050034 -21.67509 270)
			(size 0.519938 1.4986)
			(layers "F.Cu" "F.Mask" "F.Paste")
			(net "GND")
		)
		(pad "51" smd rect
			(at -2.050034 -20.824952 270)
			(size 0.519938 1.4986)
			(layers "F.Cu" "F.Mask" "F.Paste")
			(net "M_A_CPU0_SA_CB<0>")
		)
		(pad "52" smd rect
			(at -2.050034 -19.975068 270)
			(size 0.519938 1.4986)
			(layers "F.Cu" "F.Mask" "F.Paste")
			(net "GND")
		)
		(pad "53" smd rect
			(at -2.050034 -19.12493 270)
			(size 0.519938 1.4986)
			(layers "F.Cu" "F.Mask" "F.Paste")
			(net "M_A_CPU0_SA_CB<1>")
		)
		(pad "54" smd rect
			(at -2.050034 -18.275046 270)
			(size 0.519938 1.4986)
			(layers "F.Cu" "F.Mask" "F.Paste")
			(net "GND")
		)
		(pad "55" smd rect
			(at -2.050034 -17.424908 270)
			(size 0.519938 1.4986)
			(layers "F.Cu" "F.Mask" "F.Paste")
			(net "M_A_CPU0_SA_DQS_DP<4>")
		)
		(pad "56" smd rect
			(at -2.050034 -16.575024 270)
			(size 0.519938 1.4986)
			(layers "F.Cu" "F.Mask" "F.Paste")
			(net "M_A_CPU0_SA_DQS_DN<4>")
		)
		(pad "57" smd rect
			(at -2.050034 -15.724886 270)
			(size 0.519938 1.4986)
			(layers "F.Cu" "F.Mask" "F.Paste")
			(net "GND")
		)
		(pad "58" smd rect
			(at -2.050034 -14.875002 270)
			(size 0.519938 1.4986)
			(layers "F.Cu" "F.Mask" "F.Paste")
			(net "M_A_CPU0_SA_CB<4>")
		)
		(pad "59" smd rect
			(at -2.050034 -14.025118 270)
			(size 0.519938 1.4986)
			(layers "F.Cu" "F.Mask" "F.Paste")
			(net "GND")
		)
		(pad "60" smd rect
			(at -2.050034 -13.17498 270)
			(size 0.519938 1.4986)
			(layers "F.Cu" "F.Mask" "F.Paste")
			(net "M_A_CPU0_SA_CB<5>")
		)
		(pad "61" smd rect
			(at -2.050034 -12.325096 270)
			(size 0.519938 1.4986)
			(layers "F.Cu" "F.Mask" "F.Paste")
			(net "GND")
		)
		(pad "62" smd rect
			(at -2.050034 -11.474958 270)
			(size 0.519938 1.4986)
			(layers "F.Cu" "F.Mask" "F.Paste")
			(net "M_A_CPU0_ALERT_N")
		)
		(pad "63" smd rect
			(at -2.050034 -10.625074 270)
			(size 0.519938 1.4986)
			(layers "F.Cu" "F.Mask" "F.Paste")
			(net "GND")
		)
		(pad "64" smd rect
			(at -2.050034 -9.774936 270)
			(size 0.519938 1.4986)
			(layers "F.Cu" "F.Mask" "F.Paste")
			(net "M_A_CPU0_SA_CS_N<2>")
		)
		(pad "65" smd rect
			(at -2.050034 -8.925052 270)
			(size 0.519938 1.4986)
			(layers "F.Cu" "F.Mask" "F.Paste")
			(net "GND")
		)
		(pad "66" smd rect
			(at -2.050034 -8.074914 270)
			(size 0.519938 1.4986)
			(layers "F.Cu" "F.Mask" "F.Paste")
			(net "M_A_CPU0_SA_CA<0>")
		)
		(pad "67" smd rect
			(at -2.050034 -7.22503 270)
			(size 0.519938 1.4986)
			(layers "F.Cu" "F.Mask" "F.Paste")
			(net "GND")
		)
		(pad "68" smd rect
			(at -2.050034 -6.374892 270)
			(size 0.519938 1.4986)
			(layers "F.Cu" "F.Mask" "F.Paste")
			(net "M_A_CPU0_SA_CA<2>")
		)
		(pad "69" smd rect
			(at -2.050034 -5.525008 270)
			(size 0.519938 1.4986)
			(layers "F.Cu" "F.Mask" "F.Paste")
			(net "GND")
		)
		(pad "70" smd rect
			(at -2.050034 -4.675124 270)
			(size 0.519938 1.4986)
			(layers "F.Cu" "F.Mask" "F.Paste")
			(net "M_A_CPU0_SA_CA<4>")
		)
		(pad "71" smd rect
			(at -2.050034 -3.824986 270)
			(size 0.519938 1.4986)
			(layers "F.Cu" "F.Mask" "F.Paste")
			(net "GND")
		)
		(pad "72" smd rect
			(at -2.050034 -2.975102 270)
			(size 0.519938 1.4986)
			(layers "F.Cu" "F.Mask" "F.Paste")
			(net "M_A_CPU0_SA_CA<6>")
		)
		(pad "73" smd rect
			(at -2.050034 -2.124964 270)
			(size 0.519938 1.4986)
			(layers "F.Cu" "F.Mask" "F.Paste")
			(net "GND")
		)
		(pad "74" smd rect
			(at -2.050034 -1.27508 270)
			(size 0.519938 1.4986)
			(layers "F.Cu" "F.Mask" "F.Paste")
			(net "M_A_CPU0_SA_PAR")
		)
		(pad "75" smd rect
			(at -2.050034 -0.424942 270)
			(size 0.519938 1.4986)
			(layers "F.Cu" "F.Mask" "F.Paste")
			(net "GND")
		)
		(pad "76" smd rect
			(at -2.050034 5.525008 270)
			(size 0.519938 1.4986)
			(layers "F.Cu" "F.Mask" "F.Paste")
			(net "M_A_CPU0_SB_CA<0>")
		)
		(pad "77" smd rect
			(at -2.050034 6.374892 270)
			(size 0.519938 1.4986)
			(layers "F.Cu" "F.Mask" "F.Paste")
			(net "GND")
		)
		(pad "78" smd rect
			(at -2.050034 7.22503 270)
			(size 0.519938 1.4986)
			(layers "F.Cu" "F.Mask" "F.Paste")
			(net "M_A_CPU0_SB_CA<2>")
		)
		(pad "79" smd rect
			(at -2.050034 8.074914 270)
			(size 0.519938 1.4986)
			(layers "F.Cu" "F.Mask" "F.Paste")
			(net "GND")
		)
		(pad "80" smd rect
			(at -2.050034 8.925052 270)
			(size 0.519938 1.4986)
			(layers "F.Cu" "F.Mask" "F.Paste")
			(net "M_A_CPU0_SB_CA<4>")
		)
		(pad "81" smd rect
			(at -2.050034 9.774936 270)
			(size 0.519938 1.4986)
			(layers "F.Cu" "F.Mask" "F.Paste")
			(net "GND")
		)
		(pad "82" smd rect
			(at -2.050034 10.625074 270)
			(size 0.519938 1.4986)
			(layers "F.Cu" "F.Mask" "F.Paste")
			(net "M_A_CPU0_SB_CA<6>")
		)
		(pad "83" smd rect
			(at -2.050034 11.474958 270)
			(size 0.519938 1.4986)
			(layers "F.Cu" "F.Mask" "F.Paste")
			(net "GND")
		)
		(pad "84" smd rect
			(at -2.050034 12.325096 270)
			(size 0.519938 1.4986)
			(layers "F.Cu" "F.Mask" "F.Paste")
			(net "M_A_CPU0_SB_CS_N<2>")
		)
		(pad "85" smd rect
			(at -2.050034 13.17498 270)
			(size 0.519938 1.4986)
			(layers "F.Cu" "F.Mask" "F.Paste")
			(net "GND")
		)
		(pad "86" smd rect
			(at -2.050034 14.025118 270)
			(size 0.519938 1.4986)
			(layers "F.Cu" "F.Mask" "F.Paste")
			(net "M_A_CPU0_SA_RSP<1>")
		)
		(pad "87" smd rect
			(at -2.050034 14.875002 270)
			(size 0.519938 1.4986)
			(layers "F.Cu" "F.Mask" "F.Paste")
			(net "M_A_CPU0_SB_RSP<1>")
		)
		(pad "88" smd rect
			(at -2.050034 15.724886 270)
			(size 0.519938 1.4986)
			(layers "F.Cu" "F.Mask" "F.Paste")
			(net "GND")
		)
		(pad "89" smd rect
			(at -2.050034 16.575024 270)
			(size 0.519938 1.4986)
			(layers "F.Cu" "F.Mask" "F.Paste")
			(net "M_A_CPU0_SB_CB<4>")
		)
		(pad "90" smd rect
			(at -2.050034 17.424908 270)
			(size 0.519938 1.4986)
			(layers "F.Cu" "F.Mask" "F.Paste")
			(net "GND")
		)
		(pad "91" smd rect
			(at -2.050034 18.275046 270)
			(size 0.519938 1.4986)
			(layers "F.Cu" "F.Mask" "F.Paste")
			(net "M_A_CPU0_SB_CB<5>")
		)
	)
)
